# TIMECARD (Time Appliance Project (Time Card)) — schematic netlist excerpt (pin names and nets, part order shuffled) for the footprints in the layout excerpt that follows; sources: Cadence DE-HDL packaged netlist, KiCad conversion of R4006-B0001-02_R01.brd

C208  CAPACITOR  0.1UF 10V 10%  pkg SMC_0402R_H022  page 14 : \1\ = XP2R5V_FPGA ; \2\ = SG
C316  CAPACITOR  0.1UF 25V 10%  pkg SMC_0402R_H022  page 26 : \1\ = RGB_LED_SHUTDOWN_N ; \2\ = SG

(kicad_pcb
	(version 20260206)
	(generator "pcbnew")
	(generator_version "10.0")
	(general
		(thickness 1.6)
		(legacy_teardrops no)
	)
	(paper "A4")
	(title_block
		(title "timecard-production-celestica-r4006 — R4006-B0001-02_R01.brd")
		(comment 1 "Time Appliance Project (Time Card) / footprints 987-988 of 1113")
	)
	(layers
		(0 "F.Cu" signal "TOP")
		(4 "In1.Cu" signal "L02_GND1")
		(6 "In2.Cu" signal "L03_SIG1")
		(8 "In3.Cu" signal "L04_GND2")
		(10 "In4.Cu" signal "L05_VCC1")
		(12 "In5.Cu" signal "L06_VCC2")
		(14 "In6.Cu" signal "L07_GND3")
		(16 "In7.Cu" signal "L08_SIG2")
		(18 "In8.Cu" signal "L09_GND4")
		(2 "B.Cu" signal "BOTTOM")
		(9 "F.Adhes" user "F.Adhesive")
		(11 "B.Adhes" user "B.Adhesive")
		(13 "F.Paste" user "Package Geometry/Pastemask Top")
		(15 "B.Paste" user "Package Geometry/Pastemask Bottom")
		(5 "F.SilkS" user "Ref Des/Silkscreen Top")
		(7 "B.SilkS" user "Ref Des/Silkscreen Bottom")
		(1 "F.Mask" user "Board Geometry/Soldermask Top")
		(3 "B.Mask" user "Board Geometry/Soldermask Bottom")
		(17 "Dwgs.User" user "User.Drawings")
		(19 "Cmts.User" user "User.Comments")
		(21 "Eco1.User" user "User.Eco1")
		(23 "Eco2.User" user "User.Eco2")
		(25 "Edge.Cuts" user "Board Geometry/Outline")
		(27 "Margin" user)
		(31 "F.CrtYd" user "Package Geometry/Place Bound Top")
		(29 "B.CrtYd" user "Package Geometry/Place Bound Bottom")
		(35 "F.Fab" user "Ref Des/Assembly Top")
		(33 "B.Fab" user "Ref Des/Assembly Bottom")
	)
	(footprint ""
		(layer "B.Cu")
		(at 107.696 -100.6348 -90)
		(property "Reference" "C316"
			(at 2.2098 1.05537 270)
			(unlocked yes)
			(layer "B.SilkS")
			(effects
				(font
					(size 0.7874 0.5842)
					(thickness 0.1524)
				)
				(justify mirror)
			)
		)
		(property "Value" "VAL*"
			(at -0.0762 2.067306 270)
			(unlocked yes)
			(layer "B.Fab")
			(hide yes)
			(effects
				(font
					(size 0.7874 0.5842)
					(thickness 0.1524)
				)
				(justify mirror)
			)
		)
		(property "Tolerance" "TOL*"
			(at -0.0762 3.032506 270)
			(unlocked yes)
			(layer "Cmts.User")
			(hide yes)
			(effects
				(font
					(size 0.7874 0.5842)
					(thickness 0.1524)
				)
				(justify mirror)
			)
		)
		(property "User Part Number" "PARTNUM*"
			(at -0.1016 4.023106 270)
			(unlocked yes)
			(layer "Cmts.User")
			(hide yes)
			(effects
				(font
					(size 0.7874 0.5842)
					(thickness 0.1524)
				)
				(justify mirror)
			)
		)
		(property "Device Type" "CAPACITOR-G105-0B104-EK,0.1UF,A"
			(at -0.0508 1.127506 270)
			(unlocked yes)
			(layer "B.Fab")
			(hide yes)
			(effects
				(font
					(size 0.7874 0.5842)
					(thickness 0.1524)
				)
				(justify mirror)
			)
		)
		(duplicate_pad_numbers_are_jumpers no)
		(fp_line
			(start -1.143 0.5588)
			(end -1.143 -0.5588)
			(stroke
				(width 0.1)
				(type default)
			)
			(layer "B.SilkS")
		)
		(fp_line
			(start 1.143 0.5588)
			(end -1.143 0.5588)
			(stroke
				(width 0.1)
				(type default)
			)
			(layer "B.SilkS")
		)
		(fp_line
			(start -1.143 -0.5588)
			(end 1.143 -0.5588)
			(stroke
				(width 0.1)
				(type default)
			)
			(layer "B.SilkS")
		)
		(fp_line
			(start 1.143 -0.5588)
			(end 1.143 0.5588)
			(stroke
				(width 0.1)
				(type default)
			)
			(layer "B.SilkS")
		)
		(fp_poly
			(pts
				(xy 1.143 0.5588) (xy -1.143 0.5588) (xy -1.143 -0.5588) (xy 1.143 -0.5588)
			)
			(stroke
				(width 0)
				(type default)
			)
			(fill no)
			(layer "B.CrtYd")
		)
		(fp_line
			(start -0.508 0.3048)
			(end -0.508 -0.3048)
			(stroke
				(width 0.1)
				(type default)
			)
			(layer "B.Fab")
		)
		(fp_line
			(start 0.508 0.3048)
			(end -0.508 0.3048)
			(stroke
				(width 0.1)
				(type default)
			)
			(layer "B.Fab")
		)
		(fp_line
			(start -0.508 -0.3048)
			(end 0.508 -0.3048)
			(stroke
				(width 0.1)
				(type default)
			)
			(layer "B.Fab")
		)
		(fp_line
			(start 0.508 -0.3048)
			(end 0.508 0.3048)
			(stroke
				(width 0.1)
				(type default)
			)
			(layer "B.Fab")
		)
		(pad "1" smd rect
			(at 0.5334 0 90)
			(size 0.7112 0.6096)
			(layers "B.Cu" "B.Mask" "B.Paste")
			(net "RGB_LED_SHUTDOWN_N")
		)
		(pad "2" smd rect
			(at -0.5334 0 90)
			(size 0.7112 0.6096)
			(layers "B.Cu" "B.Mask" "B.Paste")
			(net "SG")
		)
		(zone
			(layer "B.Cu")
			(hatch none 0.5)
			(connect_pads
				(clearance 0)
			)
			(min_thickness 0.25)
			(keepout
				(tracks not_allowed)
				(vias allowed)
				(pads allowed)
				(copperpour not_allowed)
				(footprints allowed)
			)
			(placement
				(enabled no)
				(sheetname "")
			)
			(fill
				(thermal_gap 0.5)
				(thermal_bridge_width 0.5)
				(island_removal_mode 0)
			)
			(polygon
				(pts
					(xy 107.3912 -100.5586) (xy 108.0008 -100.5586) (xy 108.0008 -100.711) (xy 107.3912 -100.711)
				)
			)
		)
		(zone
			(layer "B.Cu")
			(hatch none 0.5)
			(connect_pads
				(clearance 0)
			)
			(min_thickness 0.25)
			(keepout
				(tracks allowed)
				(vias not_allowed)
				(pads allowed)
				(copperpour not_allowed)
				(footprints allowed)
			)
			(placement
				(enabled no)
				(sheetname "")
			)
			(fill
				(thermal_gap 0.5)
				(thermal_bridge_width 0.5)
				(island_removal_mode 0)
			)
			(polygon
				(pts
					(xy 107.3912 -100.5586) (xy 108.0008 -100.5586) (xy 108.0008 -100.711) (xy 107.3912 -100.711)
				)
			)
		)
	)
	(footprint ""
		(layer "B.Cu")
		(at 106.847132 -36.323016 -90)
		(property "Reference" "C208"
			(at 1.525016 41.600882 270)
			(unlocked yes)
			(layer "B.SilkS")
			(effects
				(font
					(size 0.635 0.4064)
					(thickness 0.1524)
				)
				(justify mirror)
			)
		)
		(property "Value" "VAL*"
			(at 0 3.718306 270)
			(unlocked yes)
			(layer "B.Fab")
			(hide yes)
			(effects
				(font
					(size 0.7874 0.5842)
					(thickness 0.127)
				)
				(justify mirror)
			)
		)
		(property "Device Type" "CAPACITOR-G105-0B104-CK,0.1UF,A"
			(at 0 1.432306 270)
			(unlocked yes)
			(layer "B.Fab")
			(hide yes)
			(effects
				(font
					(size 0.7874 0.5842)
					(thickness 0.127)
				)
				(justify mirror)
			)
		)
		(property "User Part Number" "PARTNUM*"
			(at 0 2.575306 270)
			(unlocked yes)
			(layer "Cmts.User")
			(hide yes)
			(effects
				(font
					(size 0.7874 0.5842)
					(thickness 0.127)
				)
				(justify mirror)
			)
		)
		(property "Tolerance" "TOL*"
			(at 0 4.861306 270)
			(unlocked yes)
			(layer "Cmts.User")
			(hide yes)
			(effects
				(font
					(size 0.7874 0.5842)
					(thickness 0.127)
				)
				(justify mirror)
			)
		)
		(duplicate_pad_numbers_are_jumpers no)
		(fp_line
			(start -0.970026 0.4699)
			(end 0.970026 0.4699)
			(stroke
				(width 0.1)
				(type default)
			)
			(layer "B.SilkS")
		)
		(fp_line
			(start 0.970026 0.4699)
			(end 0.970026 -0.4699)
			(stroke
				(width 0.1)
				(type default)
			)
			(layer "B.SilkS")
		)
		(fp_line
			(start -0.970026 -0.4699)
			(end -0.970026 0.4699)
			(stroke
				(width 0.1)
				(type default)
			)
			(layer "B.SilkS")
		)
		(fp_line
			(start 0.970026 -0.4699)
			(end -0.970026 -0.4699)
			(stroke
				(width 0.1)
				(type default)
			)
			(layer "B.SilkS")
		)
		(fp_poly
			(pts
				(xy 0.970026 0.4699) (xy -0.970026 0.4699) (xy -0.970026 -0.4699) (xy 0.970026 -0.4699)
			)
			(stroke
				(width 0)
				(type default)
			)
			(fill no)
			(layer "B.CrtYd")
		)
		(fp_line
			(start -0.508 0.3048)
			(end 0.508 0.3048)
			(stroke
				(width 0.1)
				(type default)
			)
			(layer "B.Fab")
		)
		(fp_line
			(start 0.508 0.3048)
			(end 0.508 -0.3048)
			(stroke
				(width 0.1)
				(type default)
			)
			(layer "B.Fab")
		)
		(fp_line
			(start -0.508 -0.3048)
			(end -0.508 0.3048)
			(stroke
				(width 0.1)
				(type default)
			)
			(layer "B.Fab")
		)
		(fp_line
			(start 0.508 -0.3048)
			(end -0.508 -0.3048)
			(stroke
				(width 0.1)
				(type default)
			)
			(layer "B.Fab")
		)
		(pad "1" smd circle
			(at 0.500126 0 90)
			(size 0.635 0.635)
			(layers "B.Cu" "B.Mask" "B.Paste")
			(net "XP2R5V_FPGA")
		)
		(pad "2" smd circle
			(at -0.500126 0 90)
			(size 0.635 0.635)
			(layers "B.Cu" "B.Mask" "B.Paste")
			(net "SG")
		)
	)
)
